G04*
G04 #@! TF.GenerationSoftware,Altium Limited,Altium Designer,23.0.1 (38)*
G04*
G04 Layer_Color=16711935*
%FSLAX44Y44*%
%MOMM*%
G71*
G04*
G04 #@! TF.SameCoordinates,9A23C038-B079-480F-8166-AFFB5740F5AE*
G04*
G04*
G04 #@! TF.FilePolarity,Positive*
G04*
G01*
G75*
%ADD10C,0.1778*%
%ADD11C,0.1524*%
%ADD12C,0.0762*%
%ADD14R,0.1010X0.0691*%
%ADD16R,1.1684X1.3970*%
%ADD42C,0.0127*%
%ADD48R,0.4500X3.4750*%
D10*
X90094Y98666D02*
X109906D01*
Y109334D01*
X90094D02*
X109906D01*
X90094Y98666D02*
Y109334D01*
X504142Y118716D02*
X516842D01*
Y90776D02*
Y118716D01*
X504142Y90776D02*
X516842D01*
X504142D02*
Y118716D01*
X103051Y202382D02*
X112703D01*
Y185618D02*
Y202382D01*
X103051Y185618D02*
X112703D01*
X103051D02*
Y202382D01*
X226750Y83250D02*
X387250D01*
X226750Y226750D02*
X387250D01*
X226750Y83250D02*
Y226750D01*
X387250Y83250D02*
Y226750D01*
X650976Y75550D02*
Y150480D01*
X570440Y75550D02*
Y150480D01*
Y75550D02*
X650976D01*
X570440Y150480D02*
X650976D01*
X-52844Y237624D02*
X96465D01*
X-52844Y158376D02*
X96465D01*
Y237624D01*
X-52844Y158376D02*
Y237624D01*
X123094Y169557D02*
X142906D01*
Y179209D01*
X123094D02*
X142906D01*
X123094Y169557D02*
Y179209D01*
X347174Y57094D02*
Y76906D01*
Y57094D02*
X356826D01*
Y76906D01*
X347174D02*
X356826D01*
X362731Y57094D02*
Y76906D01*
Y57094D02*
X372383D01*
Y76906D01*
X362731D02*
X372383D01*
X378164Y57094D02*
Y76906D01*
Y57094D02*
X387816D01*
Y76906D01*
X378164D02*
X387816D01*
X252834Y234094D02*
Y253906D01*
X243183D02*
X252834D01*
X243183Y234094D02*
Y253906D01*
Y234094D02*
X252834D01*
X435142Y118716D02*
X447842D01*
Y90776D02*
Y118716D01*
X435142Y90776D02*
X447842D01*
X435142D02*
Y118716D01*
X287666Y233094D02*
Y252906D01*
Y233094D02*
X298334D01*
Y252906D01*
X287666D02*
X298334D01*
X453666Y99094D02*
Y118906D01*
Y99094D02*
X464334D01*
Y118906D01*
X453666D02*
X464334D01*
X522666Y99094D02*
Y118906D01*
Y99094D02*
X533334D01*
Y118906D01*
X522666D02*
X533334D01*
X590393Y185094D02*
Y204906D01*
X579725D02*
X590393D01*
X579725Y185094D02*
Y204906D01*
Y185094D02*
X590393D01*
X615945D02*
Y204906D01*
X605277D02*
X615945D01*
X605277Y185094D02*
Y204906D01*
Y185094D02*
X615945D01*
X377094Y248666D02*
X396906D01*
Y259334D01*
X377094D02*
X396906D01*
X377094Y248666D02*
Y259334D01*
X121094Y109334D02*
X140906D01*
X121094Y98666D02*
Y109334D01*
Y98666D02*
X140906D01*
Y109334D01*
X216094Y66666D02*
X235906D01*
Y77334D01*
X216094D02*
X235906D01*
X216094Y66666D02*
Y77334D01*
D11*
X111475Y112474D02*
X130525D01*
X111475Y135334D02*
Y147526D01*
X130525Y112474D02*
Y115516D01*
X139542D01*
X111475Y112474D02*
Y124666D01*
X102458Y135334D02*
X111475D01*
X102458Y124666D02*
X111475D01*
Y147526D02*
X130525D01*
X139542Y115516D02*
Y144484D01*
X102458Y124666D02*
Y135334D01*
X130525Y144484D02*
X139542D01*
X130525D02*
Y147526D01*
D12*
X509285Y104429D02*
X511571D01*
X509285D02*
X510428Y105571D01*
X511571Y104429D01*
X440285D02*
X442571D01*
X440285D02*
X441428Y105571D01*
X442571Y104429D01*
D14*
X510469Y104770D02*
D03*
X441469D02*
D03*
D16*
X657072Y81657D02*
D03*
D42*
X3020Y10247D02*
G03*
X10670Y2960I7650J372D01*
G01*
X68420Y56010D02*
G03*
X55020Y68660I-13400J-772D01*
G01*
X3020Y10247D02*
G03*
X10670Y2960I7650J372D01*
G01*
X68420Y56010D02*
G03*
X55020Y68660I-13400J-772D01*
G01*
X668710Y307528D02*
G03*
X661080Y314460I-7630J-733D01*
G01*
X593410Y266830D02*
G03*
X612290Y248760I18880J828D01*
G01*
X45090Y248760D02*
G03*
X68410Y269810I0J23442D01*
G01*
X10630Y314460D02*
G03*
X3010Y306849I0J-7620D01*
G01*
X649010Y288960D02*
G03*
X649010Y288960I-15500J0D01*
G01*
X44010Y28960D02*
G03*
X44010Y28960I-15500J0D01*
G01*
X649010D02*
G03*
X649010Y28960I-15500J0D01*
G01*
X44010Y288960D02*
G03*
X44010Y288960I-15500J0D01*
G01*
X3020Y68660D02*
X55020D01*
X3020D02*
X55020D01*
X68420Y2960D02*
Y56010D01*
X10670Y2960D02*
X68420D01*
X3020Y10247D02*
Y68660D01*
X10670Y2960D02*
X68420D01*
Y56010D01*
X3020Y10247D02*
Y68660D01*
X668710Y248760D02*
Y307528D01*
X612290Y248760D02*
X668710D01*
X593410Y266830D02*
Y314460D01*
X661080D01*
X3010Y248760D02*
Y306849D01*
X68410Y269810D02*
Y314460D01*
X3010Y248760D02*
X45090D01*
X10630Y314460D02*
X68410D01*
X-3790Y0D02*
X10449D01*
X0Y-2560D02*
Y10449D01*
D48*
X385000Y209375D02*
D03*
M02*
